(kicad_pcb
	(version 20260206)
	(generator "pcbnew")
	(generator_version "10.0")
	(general
		(thickness 1.21888)
		(legacy_teardrops no)
	)
	(paper "A4")
	(title_block
		(title "timecard-v9 — TimeCard-DC-V9_EXP.PcbDoc")
		(comment 1 "Time Appliance Project (Time Card) / footprints 10-17 of 402")
	)
	(layers
		(0 "F.Cu" signal "TOP")
		(4 "In1.Cu" signal "SGND")
		(6 "In2.Cu" signal "IN1")
		(8 "In3.Cu" signal "IN2")
		(10 "In4.Cu" signal "SGND1")
		(2 "B.Cu" signal "BOTTOM")
		(9 "F.Adhes" user "F.Adhesive")
		(11 "B.Adhes" user "B.Adhesive")
		(13 "F.Paste" user "Top Paste")
		(15 "B.Paste" user "Bottom Paste")
		(5 "F.SilkS" user "Top Overlay")
		(7 "B.SilkS" user "Bottom Overlay")
		(1 "F.Mask" user "Top Solder")
		(3 "B.Mask" user "Bottom Solder")
		(17 "Dwgs.User" user "User.Drawings")
		(19 "Cmts.User" user "User.Comments")
		(21 "Eco1.User" user "User.Eco1")
		(23 "Eco2.User" user "User.Eco2")
		(25 "Edge.Cuts" user)
		(27 "Margin" user)
		(31 "F.CrtYd" user "Top Courtyard")
		(29 "B.CrtYd" user "Bottom Courtyard")
		(35 "F.Fab" user "Top Component Center")
		(33 "B.Fab" user "Bottom Component Center")
	)
	(footprint "Vault:FP-T495D107K016ATE125-MFG"
		(layer "F.Cu")
		(at 87.5216 51.9162)
		(property "Reference" "C10"
			(at -4.406655 1.1 90)
			(unlocked yes)
			(layer "F.SilkS")
			(effects
				(font
					(size 0.762 0.762)
					(thickness 0.2286)
				)
				(justify left bottom)
			)
		)
		(property "Value" "100uF_16V_2917"
			(at -2.5927 16.320035 0)
			(unlocked yes)
			(layer "F.SilkS")
			(hide yes)
			(effects
				(font
					(size 0.762 0.762)
					(thickness 0.2286)
				)
				(justify left bottom)
			)
		)
		(sheetname "03-POWER")
		(sheetfile "03-POWER.kicad_sch")
		(duplicate_pad_numbers_are_jumpers no)
		(fp_line
			(start -3.8 -2.3)
			(end 3.8 -2.3)
			(stroke
				(width 0.2)
				(type solid)
			)
			(layer "F.SilkS")
		)
		(fp_line
			(start -3.8 -1.54)
			(end -3.8 -2.3)
			(stroke
				(width 0.2)
				(type solid)
			)
			(layer "F.SilkS")
		)
		(fp_line
			(start -3.8 2.3)
			(end -3.8 1.54)
			(stroke
				(width 0.2)
				(type solid)
			)
			(layer "F.SilkS")
		)
		(fp_line
			(start -3.8 2.3)
			(end 3.8 2.3)
			(stroke
				(width 0.2)
				(type solid)
			)
			(layer "F.SilkS")
		)
		(fp_line
			(start 3.8 -1.54)
			(end 3.8 -2.3)
			(stroke
				(width 0.2)
				(type solid)
			)
			(layer "F.SilkS")
		)
		(fp_line
			(start 3.8 2.3)
			(end 3.8 1.54)
			(stroke
				(width 0.2)
				(type solid)
			)
			(layer "F.SilkS")
		)
		(fp_line
			(start 4.4 0)
			(end 5 0)
			(stroke
				(width 0.2)
				(type solid)
			)
			(layer "F.SilkS")
		)
		(fp_line
			(start 4.7 0.3)
			(end 4.7 -0.3)
			(stroke
				(width 0.2)
				(type solid)
			)
			(layer "F.SilkS")
		)
		(fp_line
			(start -4.105 -2.4)
			(end 4.105 -2.4)
			(stroke
				(width 0.2)
				(type solid)
			)
			(layer "F.CrtYd")
		)
		(fp_line
			(start -4.105 2.4)
			(end -4.105 -2.4)
			(stroke
				(width 0.2)
				(type solid)
			)
			(layer "F.CrtYd")
		)
		(fp_line
			(start -4.105 2.4)
			(end 4.105 2.4)
			(stroke
				(width 0.2)
				(type solid)
			)
			(layer "F.CrtYd")
		)
		(fp_line
			(start 4.105 2.4)
			(end 4.105 -2.4)
			(stroke
				(width 0.2)
				(type solid)
			)
			(layer "F.CrtYd")
		)
		(fp_line
			(start -4.105 -2.4)
			(end 4.105 -2.4)
			(stroke
				(width 0.2)
				(type solid)
			)
			(layer "F.Fab")
		)
		(fp_line
			(start -4.105 2.4)
			(end -4.105 -2.4)
			(stroke
				(width 0.2)
				(type solid)
			)
			(layer "F.Fab")
		)
		(fp_line
			(start -4.105 2.4)
			(end 4.105 2.4)
			(stroke
				(width 0.2)
				(type solid)
			)
			(layer "F.Fab")
		)
		(fp_line
			(start -0.5 0)
			(end 0.5 0)
			(stroke
				(width 0.1)
				(type solid)
			)
			(layer "F.Fab")
		)
		(fp_line
			(start 0 0.5)
			(end 0 -0.5)
			(stroke
				(width 0.1)
				(type solid)
			)
			(layer "F.Fab")
		)
		(fp_line
			(start 4.105 2.4)
			(end 4.105 -2.4)
			(stroke
				(width 0.2)
				(type solid)
			)
			(layer "F.Fab")
		)
		(fp_text user "${REFERENCE}"
			(at 0 0.28425 360)
			(unlocked yes)
			(layer "F.Fab")
			(effects
				(font
					(face "Arial")
					(size 0.63 0.63)
					(thickness 0.1)
				)
				(justify left bottom)
			)
		)
		(pad "1" smd rect
			(at -3.01 0)
			(size 1.99 2.33)
			(layers "F.Cu" "F.Mask" "F.Paste")
			(net "GND")
			(solder_mask_margin 0)
			(solder_paste_margin 0)
		)
		(pad "2" smd rect
			(at 3.01 0)
			(size 1.99 2.33)
			(layers "F.Cu" "F.Mask" "F.Paste")
			(net "+12V")
			(solder_mask_margin 0)
			(solder_paste_margin 0)
		)
	)
	(footprint "Vault:RESC1005X40X25NL05T05"
		(layer "F.Cu")
		(at 154.0216 118.8162)
		(property "Reference" "R75"
			(at 0.5286 1.126921 0)
			(unlocked yes)
			(layer "F.SilkS")
			(effects
				(font
					(size 0.762 0.762)
					(thickness 0.2286)
				)
			)
		)
		(property "Value" "DNI_27_1%_0402"
			(at -2.732271 9.407655 270)
			(unlocked yes)
			(layer "F.SilkS")
			(hide yes)
			(effects
				(font
					(size 0.762 0.762)
					(thickness 0.2286)
				)
			)
		)
		(sheetname "08-DIPSwitches_I2C")
		(sheetfile "08-DIPSwitches_I2C.kicad_sch")
		(duplicate_pad_numbers_are_jumpers no)
		(pad "1" smd rect
			(at -0.45 0 90)
			(size 0.55 0.55)
			(layers "F.Cu" "F.Mask" "F.Paste")
			(net "MAC_FPGA_UART_RX")
		)
		(pad "2" smd rect
			(at 0.45 0 90)
			(size 0.55 0.55)
			(layers "F.Cu" "F.Mask" "F.Paste")
			(net "MAC_RX")
		)
	)
	(footprint "Vault:FP-C3216-160-0_2-MFG"
		(layer "F.Cu")
		(at 165.8216 83.5162 180)
		(property "Reference" "C78"
			(at 2.2714 1.173079 0)
			(unlocked yes)
			(layer "F.SilkS")
			(effects
				(font
					(size 0.762 0.762)
					(thickness 0.2286)
				)
			)
		)
		(property "Value" "47uF_16V_1206"
			(at -4.014951 8.77266 90)
			(unlocked yes)
			(layer "F.SilkS")
			(hide yes)
			(effects
				(font
					(size 0.762 0.762)
					(thickness 0.2286)
				)
			)
		)
		(sheetname "03-POWER")
		(sheetfile "03-POWER.kicad_sch")
		(duplicate_pad_numbers_are_jumpers no)
		(fp_line
			(start 0.725 0.9)
			(end -0.725 0.9)
			(stroke
				(width 0.2)
				(type solid)
			)
			(layer "F.SilkS")
		)
		(fp_line
			(start 0.725 -0.9)
			(end -0.725 -0.9)
			(stroke
				(width 0.2)
				(type solid)
			)
			(layer "F.SilkS")
		)
		(fp_line
			(start 2.3 1)
			(end -2.3 1)
			(stroke
				(width 0.2)
				(type solid)
			)
			(layer "F.CrtYd")
		)
		(fp_line
			(start 2.3 -1)
			(end 2.3 1)
			(stroke
				(width 0.2)
				(type solid)
			)
			(layer "F.CrtYd")
		)
		(fp_line
			(start 2.3 -1)
			(end -2.3 -1)
			(stroke
				(width 0.2)
				(type solid)
			)
			(layer "F.CrtYd")
		)
		(fp_line
			(start -2.3 -1)
			(end -2.3 1)
			(stroke
				(width 0.2)
				(type solid)
			)
			(layer "F.CrtYd")
		)
		(fp_line
			(start 2.3 1)
			(end -2.3 1)
			(stroke
				(width 0.2)
				(type solid)
			)
			(layer "F.Fab")
		)
		(fp_line
			(start 2.3 -1)
			(end 2.3 1)
			(stroke
				(width 0.2)
				(type solid)
			)
			(layer "F.Fab")
		)
		(fp_line
			(start 2.3 -1)
			(end -2.3 -1)
			(stroke
				(width 0.2)
				(type solid)
			)
			(layer "F.Fab")
		)
		(fp_line
			(start 0.5 0)
			(end -0.5 0)
			(stroke
				(width 0.1)
				(type solid)
			)
			(layer "F.Fab")
		)
		(fp_line
			(start 0 -0.5)
			(end 0 0.5)
			(stroke
				(width 0.1)
				(type solid)
			)
			(layer "F.Fab")
		)
		(fp_line
			(start -2.3 -1)
			(end -2.3 1)
			(stroke
				(width 0.2)
				(type solid)
			)
			(layer "F.Fab")
		)
		(fp_text user "${REFERENCE}"
			(at -0.00001 0.09601 180)
			(unlocked yes)
			(layer "F.Fab")
			(effects
				(font
					(face "Arial")
					(size 0.63 0.63)
					(thickness 0.1)
				)
				(justify left bottom)
			)
		)
		(pad "1" smd rect
			(at -1.65 0 180)
			(size 1.1 1.35)
			(layers "F.Cu" "F.Mask" "F.Paste")
			(net "+3.3V")
			(solder_mask_margin 0)
			(solder_paste_margin 0)
		)
		(pad "2" smd rect
			(at 1.65 0 180)
			(size 1.1 1.35)
			(layers "F.Cu" "F.Mask" "F.Paste")
			(net "GND")
			(solder_mask_margin 0)
			(solder_paste_margin 0)
		)
	)
	(footprint "Vault:RESC1005X40X25LL05T10"
		(layer "F.Cu")
		(at 144.7216 102.2162 -90)
		(property "Reference" "R98"
			(at -2.3286 0.173079 90)
			(unlocked yes)
			(layer "F.SilkS")
			(effects
				(font
					(size 0.762 0.762)
					(thickness 0.2286)
				)
			)
		)
		(property "Value" "49.9_1%_0402"
			(at -2.579871 8.823665 180)
			(unlocked yes)
			(layer "F.SilkS")
			(hide yes)
			(effects
				(font
					(size 0.762 0.762)
					(thickness 0.2286)
				)
			)
		)
		(sheetname "09-USBUart_PPSMUX_UARTMUX")
		(sheetfile "09-USBUart_PPSMUX_UARTMUX.kicad_sch")
		(duplicate_pad_numbers_are_jumpers no)
		(pad "1" smd rect
			(at -0.375 0)
			(size 0.45 0.5)
			(layers "F.Cu" "F.Mask" "F.Paste")
			(net "MAC_PPS_IN")
		)
		(pad "2" smd rect
			(at 0.375 0)
			(size 0.45 0.5)
			(layers "F.Cu" "F.Mask" "F.Paste")
			(net "NetR98_2")
		)
	)
	(footprint "Vault:RESC1005X40X25NL05T05"
		(layer "F.Cu")
		(at 157.5216 115.0162 180)
		(property "Reference" "R76"
			(at -2.9286 -0.126921 0)
			(unlocked yes)
			(layer "F.SilkS")
			(effects
				(font
					(size 0.762 0.762)
					(thickness 0.2286)
				)
			)
		)
		(property "Value" "27_1%_0402"
			(at -2.732271 9.53462 90)
			(unlocked yes)
			(layer "F.SilkS")
			(hide yes)
			(effects
				(font
					(size 0.762 0.762)
					(thickness 0.2286)
				)
			)
		)
		(sheetname "08-DIPSwitches_I2C")
		(sheetfile "08-DIPSwitches_I2C.kicad_sch")
		(duplicate_pad_numbers_are_jumpers no)
		(pad "1" smd rect
			(at -0.45 0 270)
			(size 0.55 0.55)
			(layers "F.Cu" "F.Mask" "F.Paste")
			(net "MAC_I2C_SCL")
		)
		(pad "2" smd rect
			(at 0.45 0 270)
			(size 0.55 0.55)
			(layers "F.Cu" "F.Mask" "F.Paste")
			(net "NetR76_2")
		)
	)
	(footprint "Resistors:RESC1005X04N"
		(layer "F.Cu")
		(at 105.8216 144.6162)
		(property "Reference" "R24"
			(at -3.3 0.693345 0)
			(unlocked yes)
			(layer "F.SilkS")
			(effects
				(font
					(size 0.762 0.762)
					(thickness 0.2286)
				)
				(justify left bottom)
			)
		)
		(property "Value" "ERJ-2GE0R00X"
			(at -0.2413 3.331845 0)
			(unlocked yes)
			(layer "F.SilkS")
			(hide yes)
			(effects
				(font
					(size 0.762 0.762)
					(thickness 0.2286)
				)
				(justify left bottom)
			)
		)
		(sheetname "04-PCIe_JTAG")
		(sheetfile "04-PCIe_JTAG.kicad_sch")
		(duplicate_pad_numbers_are_jumpers no)
		(pad "1" smd rect
			(at -0.425 0 90)
			(size 0.6 0.65)
			(layers "F.Cu" "F.Mask" "F.Paste")
			(net "PRSNT")
		)
		(pad "2" smd rect
			(at 0.425 0 90)
			(size 0.6 0.65)
			(layers "F.Cu" "F.Mask" "F.Paste")
			(net "NetP2_B31")
		)
	)
	(footprint "Vault:FP-C1005-050-0_05-IPC_A"
		(layer "F.Cu")
		(at 114.8216 81.0162 -90)
		(property "Reference" "C7"
			(at -0.5 -1.106655 270)
			(unlocked yes)
			(layer "F.SilkS")
			(effects
				(font
					(size 0.762 0.762)
					(thickness 0.2286)
				)
				(justify left bottom)
			)
		)
		(property "Value" "2.2uF_16V_0402"
			(at 12.037845 11.1911 0)
			(unlocked yes)
			(layer "F.SilkS")
			(hide yes)
			(effects
				(font
					(size 0.762 0.762)
					(thickness 0.2286)
				)
				(justify left bottom)
			)
		)
		(sheetname "05-GPS_IMU_SENSORS")
		(sheetfile "05-GPS_IMU_SENSORS.kicad_sch")
		(duplicate_pad_numbers_are_jumpers no)
		(fp_line
			(start 0.83624 0.73624)
			(end -0.83624 0.73624)
			(stroke
				(width 0.2)
				(type solid)
			)
			(layer "F.SilkS")
		)
		(fp_line
			(start 0.83624 -0.73624)
			(end -0.83624 -0.73624)
			(stroke
				(width 0.2)
				(type solid)
			)
			(layer "F.SilkS")
		)
		(fp_line
			(start -1.03624 0.53624)
			(end -1.03624 -0.53624)
			(stroke
				(width 0.2)
				(type solid)
			)
			(layer "F.CrtYd")
		)
		(fp_line
			(start 1.03623 0.53624)
			(end -1.03624 0.53624)
			(stroke
				(width 0.2)
				(type solid)
			)
			(layer "F.CrtYd")
		)
		(fp_line
			(start 1.03623 0.53624)
			(end 1.03623 -0.53624)
			(stroke
				(width 0.2)
				(type solid)
			)
			(layer "F.CrtYd")
		)
		(fp_line
			(start 1.03623 -0.53624)
			(end -1.03624 -0.53624)
			(stroke
				(width 0.2)
				(type solid)
			)
			(layer "F.CrtYd")
		)
		(fp_line
			(start -1.03624 0.53624)
			(end -1.03624 -0.53624)
			(stroke
				(width 0.2)
				(type solid)
			)
			(layer "F.Fab")
		)
		(fp_line
			(start 1.03623 0.53624)
			(end -1.03624 0.53624)
			(stroke
				(width 0.2)
				(type solid)
			)
			(layer "F.Fab")
		)
		(fp_line
			(start 1.03623 0.53624)
			(end 1.03623 -0.53624)
			(stroke
				(width 0.2)
				(type solid)
			)
			(layer "F.Fab")
		)
		(fp_line
			(start 0 0.5)
			(end 0 -0.5)
			(stroke
				(width 0.1)
				(type solid)
			)
			(layer "F.Fab")
		)
		(fp_line
			(start 0.5 0)
			(end -0.5 0)
			(stroke
				(width 0.1)
				(type solid)
			)
			(layer "F.Fab")
		)
		(fp_line
			(start 1.03623 -0.53624)
			(end -1.03624 -0.53624)
			(stroke
				(width 0.2)
				(type solid)
			)
			(layer "F.Fab")
		)
		(fp_text user "${REFERENCE}"
			(at -0.00001 0.09602 270)
			(unlocked yes)
			(layer "F.Fab")
			(effects
				(font
					(face "Arial")
					(size 0.63 0.63)
					(thickness 0.1)
				)
				(justify left bottom)
			)
		)
		(pad "1" smd rect
			(at -0.46658 0 270)
			(size 0.73933 0.67248)
			(layers "F.Cu" "F.Mask" "F.Paste")
			(net "+5.0V")
			(solder_mask_margin 0)
			(solder_paste_margin 0)
		)
		(pad "2" smd rect
			(at 0.46657 0 270)
			(size 0.73933 0.67248)
			(layers "F.Cu" "F.Mask" "F.Paste")
			(net "GND")
			(solder_mask_margin 0)
			(solder_paste_margin 0)
		)
	)
	(footprint "Vault:RESC1005X40X25NL05T05"
		(layer "F.Cu")
		(at 196.9216 133.9162)
		(property "Reference" "R151"
			(at 1.3175 -0.830389 0)
			(unlocked yes)
			(layer "F.SilkS")
			(effects
				(font
					(size 0.762 0.762)
					(thickness 0.2032)
				)
			)
		)
		(property "Value" "DNI_27_1%_0402"
			(at -2.732281 10.270975 270)
			(unlocked yes)
			(layer "F.SilkS")
			(hide yes)
			(effects
				(font
					(size 0.762 0.762)
					(thickness 0.2032)
				)
			)
		)
		(sheetname "11-M2_RCB_MUX")
		(sheetfile "11-M2_RCB_MUX.kicad_sch")
		(duplicate_pad_numbers_are_jumpers no)
		(pad "1" smd rect
			(at -0.45 0 90)
			(size 0.55 0.55)
			(layers "F.Cu" "F.Mask" "F.Paste")
			(net "RCB_GPS2_TP1")
		)
		(pad "2" smd rect
			(at 0.45 0 90)
			(size 0.55 0.55)
			(layers "F.Cu" "F.Mask" "F.Paste")
			(net "GPS2_TP1")
		)
	)
)
